(kicad_pcb
	(version 20260206)
	(generator "pcbnew")
	(generator_version "10.0")
	(general
		(thickness 1.6)
		(legacy_teardrops no)
	)
	(paper "A4")
	(title_block
		(title "Bryce Canyon_R.DPB_16317-1_OCP.brd")
		(comment 1 "Bryce Canyon / footprints 1091-1097 of 2099")
	)
	(layers
		(0 "F.Cu" signal "TOP")
		(4 "In1.Cu" signal "L2GND")
		(6 "In2.Cu" signal "L3")
		(8 "In3.Cu" signal "L4VCC")
		(10 "In4.Cu" signal "L5VCC")
		(12 "In5.Cu" signal "L6")
		(14 "In6.Cu" signal "L7GND")
		(2 "B.Cu" signal "BOTTOM")
		(9 "F.Adhes" user "F.Adhesive")
		(11 "B.Adhes" user "B.Adhesive")
		(13 "F.Paste" user "Package Geometry/Pastemask Top")
		(15 "B.Paste" user "Package Geometry/Pastemask Bottom")
		(5 "F.SilkS" user "Ref Des/Silkscreen Top")
		(7 "B.SilkS" user "Ref Des/Silkscreen Bottom")
		(1 "F.Mask" user "Board Geometry/Soldermask Top")
		(3 "B.Mask" user "Board Geometry/Soldermask Bottom")
		(17 "Dwgs.User" user "User.Drawings")
		(19 "Cmts.User" user "User.Comments")
		(21 "Eco1.User" user "User.Eco1")
		(23 "Eco2.User" user "User.Eco2")
		(25 "Edge.Cuts" user "Board Geometry/Outline")
		(27 "Margin" user)
		(31 "F.CrtYd" user "Package Geometry/Place Bound Top")
		(29 "B.CrtYd" user "Package Geometry/Place Bound Bottom")
		(35 "F.Fab" user "Ref Des/Assembly Top")
		(33 "B.Fab" user "Ref Des/Assembly Bottom")
	)
	(footprint ""
		(layer "F.Cu")
		(at 201.955654 -344.193114 90)
		(property "Reference" "Q197"
			(at 0 0 90)
			(layer "F.SilkS")
			(hide yes)
			(effects
				(font
					(size 1.27 1.27)
				)
			)
		)
		(property "Value" "IRFH8201TRPBF-GP"
			(at -4.2164 -4.3688 90)
			(unlocked yes)
			(layer "F.Fab")
			(hide yes)
			(effects
				(font
					(size 1.016 1.016)
					(thickness 0.1524)
				)
			)
		)
		(property "Device Type" "PPAK-5PH42"
			(at -4.2164 -5.8928 90)
			(unlocked yes)
			(layer "F.Fab")
			(hide yes)
			(effects
				(font
					(size 1.016 1.016)
					(thickness 0.1524)
				)
			)
		)
		(duplicate_pad_numbers_are_jumpers no)
		(fp_line
			(start 2.8956 -2.794)
			(end 2.8956 4.826)
			(stroke
				(width 0.1524)
				(type default)
			)
			(layer "F.SilkS")
		)
		(fp_line
			(start -2.8956 -2.794)
			(end 2.8956 -2.794)
			(stroke
				(width 0.1524)
				(type default)
			)
			(layer "F.SilkS")
		)
		(fp_line
			(start 2.8956 4.826)
			(end -2.8956 4.826)
			(stroke
				(width 0.1524)
				(type default)
			)
			(layer "F.SilkS")
		)
		(fp_line
			(start -2.8956 4.826)
			(end -2.8956 -2.794)
			(stroke
				(width 0.1524)
				(type default)
			)
			(layer "F.SilkS")
		)
		(fp_line
			(start -1.9431 4.9276)
			(end -3.0353 4.9276)
			(stroke
				(width 0.3302)
				(type default)
			)
			(layer "F.SilkS")
		)
		(fp_line
			(start -3.0353 4.9276)
			(end -3.0353 3.9624)
			(stroke
				(width 0.3302)
				(type default)
			)
			(layer "F.SilkS")
		)
		(fp_poly
			(pts
				(xy -2.3622 5.334) (xy -1.4986 5.334) (xy -1.9304 4.9022)
			)
			(stroke
				(width 0)
				(type default)
			)
			(fill yes)
			(layer "F.SilkS")
		)
		(fp_poly
			(pts
				(xy 0.3556 -0.3556) (xy 2.6416 -0.3556) (xy 2.6416 -2.54) (xy 0.3556 -2.54)
			)
			(stroke
				(width 0)
				(type default)
			)
			(fill yes)
			(layer "F.Paste")
		)
		(fp_poly
			(pts
				(xy -2.6416 -0.3556) (xy -0.3556 -0.3556) (xy -0.3556 -2.54) (xy -2.6416 -2.54)
			)
			(stroke
				(width 0)
				(type default)
			)
			(fill yes)
			(layer "F.Paste")
		)
		(fp_poly
			(pts
				(xy 0.3556 2.54) (xy 2.6416 2.54) (xy 2.6416 0.3556) (xy 0.3556 0.3556)
			)
			(stroke
				(width 0)
				(type default)
			)
			(fill yes)
			(layer "F.Paste")
		)
		(fp_poly
			(pts
				(xy -2.6416 2.54) (xy -0.3556 2.54) (xy -0.3556 0.3556) (xy -2.6416 0.3556)
			)
			(stroke
				(width 0)
				(type default)
			)
			(fill yes)
			(layer "F.Paste")
		)
		(fp_rect
			(start -2.5781 3.9878)
			(end 2.5781 -2.1082)
			(stroke
				(width 0)
				(type default)
			)
			(fill no)
			(layer "F.CrtYd")
		)
		(fp_poly
			(pts
				(xy -3.1496 5.08) (xy -3.1496 -3.048) (xy 3.1496 -3.048) (xy 3.1496 3.9751) (xy 2.5781 3.9751) (xy 2.5781 -2.1082)
				(xy -2.5781 -2.1082) (xy -2.5781 3.9878) (xy 3.1496 3.9878) (xy 3.1496 5.08)
			)
			(stroke
				(width 0)
				(type default)
			)
			(fill no)
			(layer "F.CrtYd")
		)
		(fp_rect
			(start -3.1496 5.08)
			(end 3.1496 -3.048)
			(stroke
				(width 0)
				(type default)
			)
			(fill no)
			(layer "F.Fab")
		)
		(pad "1" smd rect
			(at -1.905 3.81 90)
			(size 0.762 1.524)
			(layers "F.Cu" "F.Mask" "F.Paste")
			(net "P12V_IN")
		)
		(pad "2" smd rect
			(at -0.635 3.81 90)
			(size 0.762 1.524)
			(layers "F.Cu" "F.Mask" "F.Paste")
			(net "P12V_IN")
		)
		(pad "3" smd rect
			(at 0.635 3.81 90)
			(size 0.762 1.524)
			(layers "F.Cu" "F.Mask" "F.Paste")
			(net "P12V_IN")
		)
		(pad "4" smd rect
			(at 1.905 3.81 90)
			(size 0.762 1.524)
			(layers "F.Cu" "F.Mask" "F.Paste")
			(net "MB0_12V_CTRL_GATE4")
		)
		(pad "5" smd rect
			(at 0 0 90)
			(size 5.2832 5.08)
			(layers "F.Cu" "F.Mask" "F.Paste")
			(net "MB0_P12V_IN_R")
		)
		(pad "6" smd rect
			(at 0.635 -2.032 90)
			(size 0.0254 0.0254)
			(layers "F.Cu" "F.Mask" "F.Paste")
			(net "MB0_P12V_IN_R")
		)
		(pad "7" smd rect
			(at -0.635 -2.032 90)
			(size 0.0254 0.0254)
			(layers "F.Cu" "F.Mask" "F.Paste")
			(net "MB0_P12V_IN_R")
		)
		(pad "8" smd rect
			(at -1.905 -2.032 90)
			(size 0.0254 0.0254)
			(layers "F.Cu" "F.Mask" "F.Paste")
			(net "MB0_P12V_IN_R")
		)
	)
	(footprint ""
		(layer "F.Cu")
		(at 239.395 -228.219 -90)
		(property "Reference" "R513"
			(at 0 0 270)
			(layer "F.SilkS")
			(hide yes)
			(effects
				(font
					(size 1.27 1.27)
				)
			)
		)
		(property "Value" "100KR2F-L1-GP"
			(at 0.064008 -3.993896 270)
			(unlocked yes)
			(layer "F.Fab")
			(hide yes)
			(effects
				(font
					(size 1.016 1.016)
					(thickness 0.1524)
				)
			)
		)
		(property "Device Type" "R402H16"
			(at 0.064008 -5.517896 270)
			(unlocked yes)
			(layer "F.Fab")
			(hide yes)
			(effects
				(font
					(size 1.016 1.016)
					(thickness 0.1524)
				)
			)
		)
		(duplicate_pad_numbers_are_jumpers no)
		(fp_line
			(start -0.508 -0.9398)
			(end -0.508 0.9398)
			(stroke
				(width 0.1524)
				(type default)
			)
			(layer "F.SilkS")
		)
		(fp_line
			(start 0.508 -0.9398)
			(end -0.508 -0.9398)
			(stroke
				(width 0.1524)
				(type default)
			)
			(layer "F.SilkS")
		)
		(fp_rect
			(start -0.508 0.9398)
			(end 0.508 -0.9398)
			(stroke
				(width 0)
				(type default)
			)
			(fill no)
			(layer "F.CrtYd")
		)
		(fp_rect
			(start -0.508 0.9398)
			(end 0.508 -0.9398)
			(stroke
				(width 0)
				(type default)
			)
			(fill no)
			(layer "F.Fab")
		)
		(pad "1" smd custom
			(at 0 -0.4445 270)
			(size 0.1397 0.1397)
			(layers "F.Cu" "F.Mask" "F.Paste")
			(net "GPIO_VCC_U10")
			(options
				(clearance outline)
				(anchor circle)
			)
			(primitives
				(gr_poly
					(pts
						(arc
							(start -0.1778 -0.2794)
							(mid -0.249642 -0.249642)
							(end -0.2794 -0.1778)
						)
						(arc
							(start -0.2794 0.1778)
							(mid -0.249642 0.249642)
							(end -0.1778 0.2794)
						)
						(arc
							(start 0.1778 0.2794)
							(mid 0.249642 0.249642)
							(end 0.2794 0.1778)
						)
						(arc
							(start 0.2794 -0.1778)
							(mid 0.249642 -0.249642)
							(end 0.1778 -0.2794)
						)
					)
					(width 0)
					(fill yes)
				)
			)
		)
		(pad "2" smd custom
			(at 0 0.4445 270)
			(size 0.1397 0.1397)
			(layers "F.Cu" "F.Mask" "F.Paste")
			(net "GND")
			(options
				(clearance outline)
				(anchor circle)
			)
			(primitives
				(gr_poly
					(pts
						(arc
							(start -0.1778 -0.2794)
							(mid -0.249642 -0.249642)
							(end -0.2794 -0.1778)
						)
						(arc
							(start -0.2794 0.1778)
							(mid -0.249642 0.249642)
							(end -0.1778 0.2794)
						)
						(arc
							(start 0.1778 0.2794)
							(mid 0.249642 0.249642)
							(end 0.2794 0.1778)
						)
						(arc
							(start 0.2794 -0.1778)
							(mid 0.249642 -0.249642)
							(end 0.1778 -0.2794)
						)
					)
					(width 0)
					(fill yes)
				)
			)
		)
	)
	(footprint ""
		(layer "F.Cu")
		(at 74.369168 -212.390228 -90)
		(property "Reference" "R172"
			(at 0 0 270)
			(layer "F.SilkS")
			(hide yes)
			(effects
				(font
					(size 1.27 1.27)
				)
			)
		)
		(property "Value" "4K7R2F-GP"
			(at 0.064008 -3.993896 270)
			(unlocked yes)
			(layer "F.Fab")
			(hide yes)
			(effects
				(font
					(size 1.016 1.016)
					(thickness 0.1524)
				)
			)
		)
		(property "Device Type" "R402H16"
			(at 0.064008 -5.517896 270)
			(unlocked yes)
			(layer "F.Fab")
			(hide yes)
			(effects
				(font
					(size 1.016 1.016)
					(thickness 0.1524)
				)
			)
		)
		(duplicate_pad_numbers_are_jumpers no)
		(fp_line
			(start -0.508 -0.9398)
			(end -0.508 0.9398)
			(stroke
				(width 0.1524)
				(type default)
			)
			(layer "F.SilkS")
		)
		(fp_line
			(start 0.508 -0.9398)
			(end -0.508 -0.9398)
			(stroke
				(width 0.1524)
				(type default)
			)
			(layer "F.SilkS")
		)
		(fp_rect
			(start -0.508 0.9398)
			(end 0.508 -0.9398)
			(stroke
				(width 0)
				(type default)
			)
			(fill no)
			(layer "F.CrtYd")
		)
		(fp_rect
			(start -0.508 0.9398)
			(end 0.508 -0.9398)
			(stroke
				(width 0)
				(type default)
			)
			(fill no)
			(layer "F.Fab")
		)
		(pad "1" smd custom
			(at 0 -0.4445 270)
			(size 0.1397 0.1397)
			(layers "F.Cu" "F.Mask" "F.Paste")
			(net "DRIVE_B_2_ACT")
			(options
				(clearance outline)
				(anchor circle)
			)
			(primitives
				(gr_poly
					(pts
						(arc
							(start -0.1778 -0.2794)
							(mid -0.249642 -0.249642)
							(end -0.2794 -0.1778)
						)
						(arc
							(start -0.2794 0.1778)
							(mid -0.249642 0.249642)
							(end -0.1778 0.2794)
						)
						(arc
							(start 0.1778 0.2794)
							(mid 0.249642 0.249642)
							(end 0.2794 0.1778)
						)
						(arc
							(start 0.2794 -0.1778)
							(mid 0.249642 -0.249642)
							(end 0.1778 -0.2794)
						)
					)
					(width 0)
					(fill yes)
				)
			)
		)
		(pad "2" smd custom
			(at 0 0.4445 270)
			(size 0.1397 0.1397)
			(layers "F.Cu" "F.Mask" "F.Paste")
			(net "GND")
			(options
				(clearance outline)
				(anchor circle)
			)
			(primitives
				(gr_poly
					(pts
						(arc
							(start -0.1778 -0.2794)
							(mid -0.249642 -0.249642)
							(end -0.2794 -0.1778)
						)
						(arc
							(start -0.2794 0.1778)
							(mid -0.249642 0.249642)
							(end -0.1778 0.2794)
						)
						(arc
							(start 0.1778 0.2794)
							(mid 0.249642 0.249642)
							(end 0.2794 0.1778)
						)
						(arc
							(start 0.2794 -0.1778)
							(mid 0.249642 -0.249642)
							(end 0.1778 -0.2794)
						)
					)
					(width 0)
					(fill yes)
				)
			)
		)
	)
	(footprint ""
		(layer "F.Cu")
		(at 331.4954 -134.62 90)
		(property "Reference" "R491"
			(at 0 0 90)
			(layer "F.SilkS")
			(hide yes)
			(effects
				(font
					(size 1.27 1.27)
				)
			)
		)
		(property "Value" "4K7R2J-2-GP"
			(at 0.064008 -3.993896 90)
			(unlocked yes)
			(layer "F.Fab")
			(hide yes)
			(effects
				(font
					(size 1.016 1.016)
					(thickness 0.1524)
				)
			)
		)
		(property "Device Type" "R402H16"
			(at 0.064008 -5.517896 90)
			(unlocked yes)
			(layer "F.Fab")
			(hide yes)
			(effects
				(font
					(size 1.016 1.016)
					(thickness 0.1524)
				)
			)
		)
		(duplicate_pad_numbers_are_jumpers no)
		(fp_line
			(start 0.508 -0.9398)
			(end -0.508 -0.9398)
			(stroke
				(width 0.1524)
				(type default)
			)
			(layer "F.SilkS")
		)
		(fp_line
			(start -0.508 -0.9398)
			(end -0.508 0.9398)
			(stroke
				(width 0.1524)
				(type default)
			)
			(layer "F.SilkS")
		)
		(fp_rect
			(start -0.508 0.9398)
			(end 0.508 -0.9398)
			(stroke
				(width 0)
				(type default)
			)
			(fill no)
			(layer "F.CrtYd")
		)
		(fp_rect
			(start -0.508 0.9398)
			(end 0.508 -0.9398)
			(stroke
				(width 0)
				(type default)
			)
			(fill no)
			(layer "F.Fab")
		)
		(pad "1" smd custom
			(at 0 -0.4445 90)
			(size 0.1397 0.1397)
			(layers "F.Cu" "F.Mask" "F.Paste")
			(net "P12V_B")
			(options
				(clearance outline)
				(anchor circle)
			)
			(primitives
				(gr_poly
					(pts
						(arc
							(start -0.1778 -0.2794)
							(mid -0.249642 -0.249642)
							(end -0.2794 -0.1778)
						)
						(arc
							(start -0.2794 0.1778)
							(mid -0.249642 0.249642)
							(end -0.1778 0.2794)
						)
						(arc
							(start 0.1778 0.2794)
							(mid 0.249642 0.249642)
							(end 0.2794 0.1778)
						)
						(arc
							(start 0.2794 -0.1778)
							(mid 0.249642 -0.249642)
							(end 0.1778 -0.2794)
						)
					)
					(width 0)
					(fill yes)
				)
			)
		)
		(pad "2" smd custom
			(at 0 0.4445 90)
			(size 0.1397 0.1397)
			(layers "F.Cu" "F.Mask" "F.Paste")
			(net "SW_HDD_P18")
			(options
				(clearance outline)
				(anchor circle)
			)
			(primitives
				(gr_poly
					(pts
						(arc
							(start -0.1778 -0.2794)
							(mid -0.249642 -0.249642)
							(end -0.2794 -0.1778)
						)
						(arc
							(start -0.2794 0.1778)
							(mid -0.249642 0.249642)
							(end -0.1778 0.2794)
						)
						(arc
							(start 0.1778 0.2794)
							(mid 0.249642 0.249642)
							(end 0.2794 0.1778)
						)
						(arc
							(start 0.2794 -0.1778)
							(mid 0.249642 -0.249642)
							(end 0.1778 -0.2794)
						)
					)
					(width 0)
					(fill yes)
				)
			)
		)
	)
	(footprint ""
		(layer "F.Cu")
		(at 281.94 -337.185 -90)
		(property "Reference" "C33"
			(at 0 0 270)
			(layer "F.SilkS")
			(hide yes)
			(effects
				(font
					(size 1.27 1.27)
				)
			)
		)
		(property "Value" "SC1U16V3KX-5GP"
			(at 0 -2.8194 270)
			(unlocked yes)
			(layer "F.Fab")
			(hide yes)
			(effects
				(font
					(size 1.016 1.016)
					(thickness 0.1524)
				)
			)
		)
		(property "Device Type" "C603H36"
			(at 0 -4.3434 270)
			(unlocked yes)
			(layer "F.Fab")
			(hide yes)
			(effects
				(font
					(size 1.016 1.016)
					(thickness 0.1524)
				)
			)
		)
		(duplicate_pad_numbers_are_jumpers no)
		(fp_line
			(start 0.508 0)
			(end -0.508 0)
			(stroke
				(width 0.2032)
				(type default)
			)
			(layer "F.SilkS")
		)
		(fp_rect
			(start -0.5842 1.3335)
			(end 0.5842 -1.3335)
			(stroke
				(width 0)
				(type default)
			)
			(fill no)
			(layer "F.CrtYd")
		)
		(fp_rect
			(start -0.5842 1.3335)
			(end 0.5842 -1.3335)
			(stroke
				(width 0)
				(type default)
			)
			(fill no)
			(layer "F.Fab")
		)
		(pad "1" smd custom
			(at 0 -0.762 270)
			(size 0.2159 0.2159)
			(layers "F.Cu" "F.Mask" "F.Paste")
			(net "P3V3_IN")
			(options
				(clearance outline)
				(anchor circle)
			)
			(primitives
				(gr_poly
					(pts
						(arc
							(start -0.3302 -0.4318)
							(mid -0.402042 -0.402042)
							(end -0.4318 -0.3302)
						)
						(arc
							(start -0.4318 0.3302)
							(mid -0.402042 0.402042)
							(end -0.3302 0.4318)
						)
						(arc
							(start 0.3302 0.4318)
							(mid 0.402042 0.402042)
							(end 0.4318 0.3302)
						)
						(arc
							(start 0.4318 -0.3302)
							(mid 0.402042 -0.402042)
							(end 0.3302 -0.4318)
						)
					)
					(width 0)
					(fill yes)
				)
			)
		)
		(pad "2" smd custom
			(at 0 0.762 270)
			(size 0.2159 0.2159)
			(layers "F.Cu" "F.Mask" "F.Paste")
			(net "GND")
			(options
				(clearance outline)
				(anchor circle)
			)
			(primitives
				(gr_poly
					(pts
						(arc
							(start -0.3302 -0.4318)
							(mid -0.402042 -0.402042)
							(end -0.4318 -0.3302)
						)
						(arc
							(start -0.4318 0.3302)
							(mid -0.402042 0.402042)
							(end -0.3302 0.4318)
						)
						(arc
							(start 0.3302 0.4318)
							(mid 0.402042 0.402042)
							(end 0.4318 0.3302)
						)
						(arc
							(start 0.4318 -0.3302)
							(mid 0.402042 -0.402042)
							(end 0.3302 -0.4318)
						)
					)
					(width 0)
					(fill yes)
				)
			)
		)
	)
	(footprint ""
		(layer "F.Cu")
		(at 181.483 -148.209)
		(property "Reference" "R460"
			(at 0 0 0)
			(layer "F.SilkS")
			(hide yes)
			(effects
				(font
					(size 1.27 1.27)
				)
			)
		)
		(property "Value" "2R6F-GP"
			(at -0.0508 -4.8514 0)
			(unlocked yes)
			(layer "F.Fab")
			(hide yes)
			(effects
				(font
					(size 1.016 1.016)
					(thickness 0.1524)
				)
			)
		)
		(property "Device Type" "R1206H26"
			(at 0 -6.3754 0)
			(unlocked yes)
			(layer "F.Fab")
			(hide yes)
			(effects
				(font
					(size 1.016 1.016)
					(thickness 0.1524)
				)
			)
		)
		(duplicate_pad_numbers_are_jumpers no)
		(fp_line
			(start -1.016 -2.2352)
			(end 1.016 -2.2352)
			(stroke
				(width 0.1524)
				(type default)
			)
			(layer "F.SilkS")
		)
		(fp_line
			(start -1.016 2.2352)
			(end -1.016 -2.2352)
			(stroke
				(width 0.1524)
				(type default)
			)
			(layer "F.SilkS")
		)
		(fp_line
			(start 1.016 -2.2352)
			(end 1.016 2.2352)
			(stroke
				(width 0.1524)
				(type default)
			)
			(layer "F.SilkS")
		)
		(fp_line
			(start 1.016 2.2352)
			(end -1.016 2.2352)
			(stroke
				(width 0.1524)
				(type default)
			)
			(layer "F.SilkS")
		)
		(fp_rect
			(start -1.0922 2.3114)
			(end 1.0922 -2.3114)
			(stroke
				(width 0)
				(type default)
			)
			(fill no)
			(layer "F.CrtYd")
		)
		(fp_poly
			(pts
				(xy -1.0922 -2.3114) (xy 1.0922 -2.3114) (xy 1.0922 2.3114) (xy -1.0922 2.3114)
			)
			(stroke
				(width 0)
				(type default)
			)
			(fill no)
			(layer "F.Fab")
		)
		(pad "1" smd rect
			(at 0 -1.397)
			(size 1.651 1.27)
			(layers "F.Cu" "F.Mask" "F.Paste")
			(net "P5V_HDD17")
		)
		(pad "2" smd rect
			(at 0 1.397)
			(size 1.651 1.27)
			(layers "F.Cu" "F.Mask" "F.Paste")
			(net "5V_PRE_17")
		)
	)
	(footprint ""
		(layer "F.Cu")
		(at 118.618 -42.291)
		(property "Reference" "C386"
			(at 0 0 0)
			(layer "F.SilkS")
			(hide yes)
			(effects
				(font
					(size 1.27 1.27)
				)
			)
		)
		(property "Value" "SC4D7U25V5KX-1-GP"
			(at -0.0762 -6.1214 0)
			(unlocked yes)
			(layer "F.Fab")
			(hide yes)
			(effects
				(font
					(size 1.016 1.016)
					(thickness 0.1524)
				)
			)
		)
		(property "Device Type" "C805H58"
			(at -0.0762 -8.1534 0)
			(unlocked yes)
			(layer "F.Fab")
			(hide yes)
			(effects
				(font
					(size 1.016 1.016)
					(thickness 0.1524)
				)
			)
		)
		(duplicate_pad_numbers_are_jumpers no)
		(fp_line
			(start 0.635 0)
			(end -0.635 0)
			(stroke
				(width 0.508)
				(type default)
			)
			(layer "F.SilkS")
		)
		(fp_rect
			(start -0.9652 1.778)
			(end 0.9652 -1.778)
			(stroke
				(width 0)
				(type default)
			)
			(fill no)
			(layer "F.CrtYd")
		)
		(fp_poly
			(pts
				(xy -0.9652 -1.778) (xy 0.9652 -1.778) (xy 0.9652 1.778) (xy -0.9652 1.778)
			)
			(stroke
				(width 0)
				(type default)
			)
			(fill no)
			(layer "F.Fab")
		)
		(pad "1" smd rect
			(at 0 -0.9652)
			(size 1.397 1.143)
			(layers "F.Cu" "F.Mask" "F.Paste")
			(net "P12V_HDD27")
		)
		(pad "2" smd rect
			(at 0 0.9652)
			(size 1.397 1.143)
			(layers "F.Cu" "F.Mask" "F.Paste")
			(net "GND")
		)
	)
)
